# BASEBOARD_FAB2 (Tioga Pass) — schematic netlist excerpt (pin names and nets, part order shuffled) for the footprints in the layout excerpt that follows; sources: Cadence DE-HDL packaged netlist, KiCad conversion of Wiwynn_Tioga_Pass_MB.brd

C9F5  CAP_A  0.1UF 16V 10% X7R  pkg 0402V  page 239 : A = P3V3_STBY ; B = GND
CF4  SC22P50V2JN-4GP  5%  pkg SMD-BCG  page 201 : \1\ = VR_PVCCIN_CPU0_AIREF4 ; \2\ = ISENSE_PVCCIN_CPU0_PH4_IMON

(kicad_pcb
	(version 20260206)
	(generator "pcbnew")
	(generator_version "10.0")
	(general
		(thickness 1.6)
		(legacy_teardrops no)
	)
	(paper "A4")
	(title_block
		(title "Wiwynn_Tioga_Pass_MB.brd")
		(comment 1 "Tioga Pass / footprints 2094-2095 of 4770")
	)
	(layers
		(0 "F.Cu" signal "TOP")
		(4 "In1.Cu" signal "L2GND")
		(6 "In2.Cu" signal "L3")
		(8 "In3.Cu" signal "L4GND")
		(10 "In4.Cu" signal "L5")
		(12 "In5.Cu" signal "L6GND")
		(14 "In6.Cu" signal "L7VCC")
		(16 "In7.Cu" signal "L8VCC")
		(18 "In8.Cu" signal "L9GND")
		(20 "In9.Cu" signal "L10")
		(22 "In10.Cu" signal "L11GND")
		(24 "In11.Cu" signal "L12")
		(26 "In12.Cu" signal "L13GND")
		(2 "B.Cu" signal "BOTTOM")
		(9 "F.Adhes" user "F.Adhesive")
		(11 "B.Adhes" user "B.Adhesive")
		(13 "F.Paste" user "Package Geometry/Pastemask Top")
		(15 "B.Paste" user "Package Geometry/Pastemask Bottom")
		(5 "F.SilkS" user "Ref Des/Silkscreen Top")
		(7 "B.SilkS" user "Ref Des/Silkscreen Bottom")
		(1 "F.Mask" user "Board Geometry/Soldermask Top")
		(3 "B.Mask" user "Board Geometry/Soldermask Bottom")
		(17 "Dwgs.User" user "User.Drawings")
		(19 "Cmts.User" user "User.Comments")
		(21 "Eco1.User" user "User.Eco1")
		(23 "Eco2.User" user "User.Eco2")
		(25 "Edge.Cuts" user "Board Geometry/Outline")
		(27 "Margin" user)
		(31 "F.CrtYd" user "Package Geometry/Place Bound Top")
		(29 "B.CrtYd" user "Package Geometry/Place Bound Bottom")
		(35 "F.Fab" user "Ref Des/Assembly Top")
		(33 "B.Fab" user "Ref Des/Assembly Bottom")
	)
	(footprint ""
		(layer "F.Cu")
		(at 467.995 -42.164 180)
		(property "Reference" "C9F5"
			(at 0 0 180)
			(layer "F.SilkS")
			(hide yes)
			(effects
				(font
					(size 1.27 1.27)
				)
			)
		)
		(property "Value" ""
			(at 0 0 180)
			(layer "F.Fab")
			(effects
				(font
					(size 1.27 1.27)
				)
			)
		)
		(duplicate_pad_numbers_are_jumpers no)
		(fp_poly
			(pts
				(xy 0.3048 -0.1016) (xy 0.3048 0.9906) (xy -0.3048 0.9906) (xy -0.3048 -0.1016)
			)
			(stroke
				(width 0)
				(type default)
			)
			(fill no)
			(layer "F.CrtYd")
		)
		(fp_line
			(start 0.3048 0.9906)
			(end 0.3048 -0.1016)
			(stroke
				(width 0.1)
				(type default)
			)
			(layer "F.Fab")
		)
		(fp_line
			(start 0.3048 -0.1016)
			(end -0.3048 -0.1016)
			(stroke
				(width 0.1)
				(type default)
			)
			(layer "F.Fab")
		)
		(fp_line
			(start -0.3048 0.9906)
			(end 0.3048 0.9906)
			(stroke
				(width 0.1)
				(type default)
			)
			(layer "F.Fab")
		)
		(fp_line
			(start -0.3048 -0.1016)
			(end -0.3048 0.9906)
			(stroke
				(width 0.1)
				(type default)
			)
			(layer "F.Fab")
		)
		(pad "1" smd rect
			(at 0 0 180)
			(size 0.508 0.508)
			(layers "F.Cu" "F.Mask" "F.Paste")
			(net "P3V3_STBY")
		)
		(pad "2" smd rect
			(at 0 0.889 180)
			(size 0.508 0.508)
			(layers "F.Cu" "F.Mask" "F.Paste")
			(net "GND")
		)
		(zone
			(layer "F.Cu")
			(hatch none 0.5)
			(connect_pads
				(clearance 0)
			)
			(min_thickness 0.25)
			(keepout
				(tracks not_allowed)
				(vias allowed)
				(pads allowed)
				(copperpour not_allowed)
				(footprints allowed)
			)
			(placement
				(enabled no)
				(sheetname "")
			)
			(fill
				(thermal_gap 0.5)
				(thermal_bridge_width 0.5)
				(island_removal_mode 0)
			)
			(polygon
				(pts
					(xy 468.249 -42.799) (xy 467.741 -42.799) (xy 467.741 -42.418) (xy 468.249 -42.418)
				)
			)
		)
		(zone
			(layer "F.Cu")
			(hatch none 0.5)
			(connect_pads
				(clearance 0)
			)
			(min_thickness 0.25)
			(keepout
				(tracks allowed)
				(vias not_allowed)
				(pads allowed)
				(copperpour not_allowed)
				(footprints allowed)
			)
			(placement
				(enabled no)
				(sheetname "")
			)
			(fill
				(thermal_gap 0.5)
				(thermal_bridge_width 0.5)
				(island_removal_mode 0)
			)
			(polygon
				(pts
					(xy 468.249 -42.418) (xy 467.741 -42.418) (xy 467.741 -42.799) (xy 468.249 -42.799)
				)
			)
		)
	)
	(footprint ""
		(layer "F.Cu")
		(at 190.9318 -69.8754 180)
		(property "Reference" "CF4"
			(at 0 0 180)
			(layer "F.SilkS")
			(hide yes)
			(effects
				(font
					(size 1.27 1.27)
				)
			)
		)
		(property "Value" "*"
			(at 1.1811 -2.8194 180)
			(unlocked yes)
			(layer "F.Fab")
			(hide yes)
			(effects
				(font
					(size 1.27 1.016)
					(thickness 0.1524)
				)
			)
		)
		(property "Device Type" "SC22P50V2JN-4GP_SMD-BCG-SC22P5A"
			(at 1.1811 -4.3434 180)
			(unlocked yes)
			(layer "F.Fab")
			(hide yes)
			(effects
				(font
					(size 1.27 1.016)
					(thickness 0.1524)
				)
			)
		)
		(duplicate_pad_numbers_are_jumpers no)
		(fp_rect
			(start -0.4318 0.9525)
			(end 0.4318 -0.9525)
			(stroke
				(width 0)
				(type default)
			)
			(fill no)
			(layer "F.CrtYd")
		)
		(fp_rect
			(start -0.4318 0.9525)
			(end 0.4318 -0.9525)
			(stroke
				(width 0)
				(type default)
			)
			(fill no)
			(layer "F.Fab")
		)
		(pad "1" smd custom
			(at 0 -0.4445 180)
			(size 0.1524 0.1524)
			(layers "F.Cu" "F.Mask" "F.Paste")
			(net "VR_PVCCIN_CPU0_AIREF4")
			(options
				(clearance outline)
				(anchor circle)
			)
			(primitives
				(gr_poly
					(pts
						(arc
							(start 0.3048 -0.2032)
							(mid 0.275042 -0.275042)
							(end 0.2032 -0.3048)
						)
						(arc
							(start -0.2032 -0.3048)
							(mid -0.275042 -0.275042)
							(end -0.3048 -0.2032)
						)
						(arc
							(start -0.3048 0.2032)
							(mid -0.275042 0.275042)
							(end -0.2032 0.3048)
						)
						(arc
							(start 0.2032 0.3048)
							(mid 0.275042 0.275042)
							(end 0.3048 0.2032)
						)
					)
					(width 0)
					(fill yes)
				)
			)
		)
		(pad "2" smd custom
			(at 0 0.4445 180)
			(size 0.1524 0.1524)
			(layers "F.Cu" "F.Mask" "F.Paste")
			(net "ISENSE_PVCCIN_CPU0_PH4_IMON")
			(options
				(clearance outline)
				(anchor circle)
			)
			(primitives
				(gr_poly
					(pts
						(arc
							(start 0.3048 -0.2032)
							(mid 0.275042 -0.275042)
							(end 0.2032 -0.3048)
						)
						(arc
							(start -0.2032 -0.3048)
							(mid -0.275042 -0.275042)
							(end -0.3048 -0.2032)
						)
						(arc
							(start -0.3048 0.2032)
							(mid -0.275042 0.275042)
							(end -0.2032 0.3048)
						)
						(arc
							(start 0.2032 0.3048)
							(mid 0.275042 0.275042)
							(end 0.3048 0.2032)
						)
					)
					(width 0)
					(fill yes)
				)
			)
		)
	)
)
